(kicad_pcb
	(version 20260206)
	(generator "pcbnew")
	(generator_version "10.0")
	(general
		(thickness 1.6)
		(legacy_teardrops no)
	)
	(paper "A4")
	(title_block
		(title "Bryce Canyon_R.DPB_16317-1_OCP.brd")
		(comment 1 "Bryce Canyon / footprints 843-845 of 2099")
	)
	(layers
		(0 "F.Cu" signal "TOP")
		(4 "In1.Cu" signal "L2GND")
		(6 "In2.Cu" signal "L3")
		(8 "In3.Cu" signal "L4VCC")
		(10 "In4.Cu" signal "L5VCC")
		(12 "In5.Cu" signal "L6")
		(14 "In6.Cu" signal "L7GND")
		(2 "B.Cu" signal "BOTTOM")
		(9 "F.Adhes" user "F.Adhesive")
		(11 "B.Adhes" user "B.Adhesive")
		(13 "F.Paste" user "Package Geometry/Pastemask Top")
		(15 "B.Paste" user "Package Geometry/Pastemask Bottom")
		(5 "F.SilkS" user "Ref Des/Silkscreen Top")
		(7 "B.SilkS" user "Ref Des/Silkscreen Bottom")
		(1 "F.Mask" user "Board Geometry/Soldermask Top")
		(3 "B.Mask" user "Board Geometry/Soldermask Bottom")
		(17 "Dwgs.User" user "User.Drawings")
		(19 "Cmts.User" user "User.Comments")
		(21 "Eco1.User" user "User.Eco1")
		(23 "Eco2.User" user "User.Eco2")
		(25 "Edge.Cuts" user "Board Geometry/Outline")
		(27 "Margin" user)
		(31 "F.CrtYd" user "Package Geometry/Place Bound Top")
		(29 "B.CrtYd" user "Package Geometry/Place Bound Bottom")
		(35 "F.Fab" user "Ref Des/Assembly Top")
		(33 "B.Fab" user "Ref Des/Assembly Bottom")
	)
	(footprint ""
		(layer "F.Cu")
		(at 483.300024 -258.910074 -90)
		(property "Reference" "HDDSAS11"
			(at 0 0 270)
			(layer "F.SilkS")
			(hide yes)
			(effects
				(font
					(size 1.27 1.27)
				)
			)
		)
		(property "Value" "SKT-SAS15P-14P-45-GP"
			(at -20.7645 -8.9789 270)
			(unlocked yes)
			(layer "F.Fab")
			(hide yes)
			(effects
				(font
					(size 1.016 1.016)
					(thickness 0.1524)
				)
			)
		)
		(property "Device Type" "10120818-001C-TRLF"
			(at -20.7645 -10.5029 270)
			(unlocked yes)
			(layer "F.Fab")
			(hide yes)
			(effects
				(font
					(size 1.016 1.016)
					(thickness 0.1524)
				)
			)
		)
		(duplicate_pad_numbers_are_jumpers no)
		(fp_line
			(start 1.651 4.2926)
			(end 1.651 3.0099)
			(stroke
				(width 0.1524)
				(type default)
			)
			(layer "F.SilkS")
		)
		(fp_line
			(start 8.509 4.2926)
			(end 1.651 4.2926)
			(stroke
				(width 0.1524)
				(type default)
			)
			(layer "F.SilkS")
		)
		(fp_line
			(start -23.4188 3.0099)
			(end -23.4188 -3.2512)
			(stroke
				(width 0.1524)
				(type default)
			)
			(layer "F.SilkS")
		)
		(fp_line
			(start 1.651 3.0099)
			(end -23.4188 3.0099)
			(stroke
				(width 0.1524)
				(type default)
			)
			(layer "F.SilkS")
		)
		(fp_line
			(start 8.509 3.0099)
			(end 8.509 4.2926)
			(stroke
				(width 0.1524)
				(type default)
			)
			(layer "F.SilkS")
		)
		(fp_line
			(start 23.4188 3.0099)
			(end 8.509 3.0099)
			(stroke
				(width 0.1524)
				(type default)
			)
			(layer "F.SilkS")
		)
		(fp_line
			(start -23.4188 -3.2512)
			(end 23.4188 -3.2512)
			(stroke
				(width 0.1524)
				(type default)
			)
			(layer "F.SilkS")
		)
		(fp_line
			(start 23.4188 -3.2512)
			(end 23.4188 3.0099)
			(stroke
				(width 0.1524)
				(type default)
			)
			(layer "F.SilkS")
		)
		(fp_line
			(start 15.5067 -3.3401)
			(end 16.2687 -3.3401)
			(stroke
				(width 0.3302)
				(type default)
			)
			(layer "F.SilkS")
		)
		(fp_poly
			(pts
				(xy 15.868904 -3.230372) (xy 16.503904 -3.865372) (xy 15.233904 -3.865372)
			)
			(stroke
				(width 0)
				(type default)
			)
			(fill yes)
			(layer "F.SilkS")
		)
		(fp_poly
			(pts
				(xy -22.8727 -2.7559) (xy 22.8727 -2.7559) (xy 22.8727 2.7559) (xy 8.255 2.7559) (xy 8.255 3.5179)
				(xy 1.905 3.5179) (xy 1.905 2.7559) (xy -22.8727 2.7559)
			)
			(stroke
				(width 0)
				(type default)
			)
			(fill no)
			(layer "F.CrtYd")
		)
		(fp_poly
			(pts
				(xy 1.397 4.5466) (xy 1.397 3.2639) (xy -23.6728 3.2639) (xy -23.6728 -3.5052) (xy 23.6728 -3.5052)
				(xy 23.6728 -0.00635) (xy 22.8727 -0.00635) (xy 22.8727 -2.7559) (xy -22.8727 -2.7559) (xy -22.8727 2.7559)
				(xy 1.905 2.7559) (xy 1.905 3.5179) (xy 8.255 3.5179) (xy 8.255 2.7559) (xy 22.8727 2.7559) (xy 22.8727 0.00635)
				(xy 23.6728 0.00635) (xy 23.6728 3.2639) (xy 8.763 3.2639) (xy 8.763 4.5466)
			)
			(stroke
				(width 0)
				(type default)
			)
			(fill no)
			(layer "F.CrtYd")
		)
		(fp_poly
			(pts
				(xy 1.397 4.5466) (xy 1.397 3.2639) (xy -23.6728 3.2639) (xy -23.6728 -3.5052) (xy 23.6728 -3.5052)
				(xy 23.6728 3.2639) (xy 8.763 3.2639) (xy 8.763 4.5466)
			)
			(stroke
				(width 0)
				(type default)
			)
			(fill no)
			(layer "F.Fab")
		)
		(pad "" np_thru_hole circle
			(at -18.874994 0 270)
			(size 0.254 0.254)
			(drill 1.3462)
			(layers "*.Cu" "*.Mask")
			(clearance 0.9017)
			(thermal_gap 0.9017)
		)
		(pad "" np_thru_hole circle
			(at 18.874994 0 270)
			(size 0.254 0.254)
			(drill 0.9398)
			(layers "*.Cu" "*.Mask")
			(clearance 0.6985)
			(thermal_gap 0.6985)
		)
		(pad "G1" smd rect
			(at 21.874988 0 270)
			(size 2.5908 2.5908)
			(layers "F.Cu" "F.Mask" "F.Paste")
			(net "GND")
		)
		(pad "G2" smd rect
			(at -21.874988 0 270)
			(size 2.5908 2.5908)
			(layers "F.Cu" "F.Mask" "F.Paste")
			(net "GND")
		)
		(pad "P1" smd rect
			(at 1.905 -1.82499 270)
			(size 0.6096 2.3622)
			(layers "F.Cu" "F.Mask" "F.Paste")
			(net "Net_1749")
		)
		(pad "P2" smd rect
			(at 0.635 -1.82499 270)
			(size 0.6096 2.3622)
			(layers "F.Cu" "F.Mask" "F.Paste")
			(net "Net_1750")
		)
		(pad "P3" smd rect
			(at -0.635 -1.82499 270)
			(size 0.6096 2.3622)
			(layers "F.Cu" "F.Mask" "F.Paste")
			(net "Net_1751")
		)
		(pad "P4" smd rect
			(at -1.905 -1.82499 270)
			(size 0.6096 2.3622)
			(layers "F.Cu" "F.Mask" "F.Paste")
			(net "GND")
		)
		(pad "P5" smd rect
			(at -3.175 -1.82499 270)
			(size 0.6096 2.3622)
			(layers "F.Cu" "F.Mask" "F.Paste")
			(net "HDD_PRSNT_11")
		)
		(pad "P6" smd rect
			(at -4.445 -1.82499 270)
			(size 0.6096 2.3622)
			(layers "F.Cu" "F.Mask" "F.Paste")
			(net "GND")
		)
		(pad "P7" smd rect
			(at -5.715 -1.82499 270)
			(size 0.6096 2.3622)
			(layers "F.Cu" "F.Mask" "F.Paste")
			(net "5V_PRE_11")
		)
		(pad "P8" smd rect
			(at -6.985 -1.82499 270)
			(size 0.6096 2.3622)
			(layers "F.Cu" "F.Mask" "F.Paste")
			(net "P5V_HDD11")
		)
		(pad "P9" smd rect
			(at -8.255 -1.82499 270)
			(size 0.6096 2.3622)
			(layers "F.Cu" "F.Mask" "F.Paste")
			(net "P5V_HDD11")
		)
		(pad "P10" smd rect
			(at -9.525 -1.82499 270)
			(size 0.6096 2.3622)
			(layers "F.Cu" "F.Mask" "F.Paste")
			(net "GND")
		)
		(pad "P11" smd rect
			(at -10.795 -1.82499 270)
			(size 0.6096 2.3622)
			(layers "F.Cu" "F.Mask" "F.Paste")
			(net "ACT_HDD_11")
		)
		(pad "P12" smd rect
			(at -12.065 -1.82499 270)
			(size 0.6096 2.3622)
			(layers "F.Cu" "F.Mask" "F.Paste")
			(net "GND")
		)
		(pad "P13" smd rect
			(at -13.335 -1.82499 270)
			(size 0.6096 2.3622)
			(layers "F.Cu" "F.Mask" "F.Paste")
			(net "12V_PRE_11")
		)
		(pad "P14" smd rect
			(at -14.605 -1.82499 270)
			(size 0.6096 2.3622)
			(layers "F.Cu" "F.Mask" "F.Paste")
			(net "P12V_HDD11")
		)
		(pad "P15" smd rect
			(at -15.875 -1.82499 270)
			(size 0.6096 2.3622)
			(layers "F.Cu" "F.Mask" "F.Paste")
			(net "P12V_HDD11")
		)
		(pad "S1" smd rect
			(at 15.875 -1.82499 270)
			(size 0.6096 2.3622)
			(layers "F.Cu" "F.Mask" "F.Paste")
			(net "GND")
		)
		(pad "S2" smd rect
			(at 14.605 -1.82499 270)
			(size 0.6096 2.3622)
			(layers "F.Cu" "F.Mask" "F.Paste")
			(net "SAS_HDD_RX_P11")
		)
		(pad "S3" smd rect
			(at 13.335 -1.82499 270)
			(size 0.6096 2.3622)
			(layers "F.Cu" "F.Mask" "F.Paste")
			(net "SAS_HDD_RX_N11")
		)
		(pad "S4" smd rect
			(at 12.065 -1.82499 270)
			(size 0.6096 2.3622)
			(layers "F.Cu" "F.Mask" "F.Paste")
			(net "GND")
		)
		(pad "S5" smd rect
			(at 10.795 -1.82499 270)
			(size 0.6096 2.3622)
			(layers "F.Cu" "F.Mask" "F.Paste")
			(net "PHY_DRV_B_TO_SCC_B_11_DN")
		)
		(pad "S6" smd rect
			(at 9.525 -1.82499 270)
			(size 0.6096 2.3622)
			(layers "F.Cu" "F.Mask" "F.Paste")
			(net "PHY_DRV_B_TO_SCC_B_11_DP")
		)
		(pad "S7" smd rect
			(at 8.255 -1.82499 270)
			(size 0.6096 2.3622)
			(layers "F.Cu" "F.Mask" "F.Paste")
			(net "GND")
		)
		(pad "S8" smd rect
			(at 7.480046 2.845054 270)
			(size 0.508 2.3622)
			(layers "F.Cu" "F.Mask" "F.Paste")
			(net "GND")
		)
		(pad "S9" smd rect
			(at 6.679946 2.845054 270)
			(size 0.508 2.3622)
			(layers "F.Cu" "F.Mask" "F.Paste")
			(net "Net_434")
		)
		(pad "S10" smd rect
			(at 5.8801 2.845054 270)
			(size 0.508 2.3622)
			(layers "F.Cu" "F.Mask" "F.Paste")
			(net "Net_326")
		)
		(pad "S11" smd rect
			(at 5.08 2.845054 270)
			(size 0.508 2.3622)
			(layers "F.Cu" "F.Mask" "F.Paste")
			(net "GND")
		)
		(pad "S12" smd rect
			(at 4.2799 2.845054 270)
			(size 0.508 2.3622)
			(layers "F.Cu" "F.Mask" "F.Paste")
			(net "Net_362")
		)
		(pad "S13" smd rect
			(at 3.480054 2.845054 270)
			(size 0.508 2.3622)
			(layers "F.Cu" "F.Mask" "F.Paste")
			(net "Net_398")
		)
		(pad "S14" smd rect
			(at 2.679954 2.845054 270)
			(size 0.508 2.3622)
			(layers "F.Cu" "F.Mask" "F.Paste")
			(net "GND")
		)
		(zone
			(layer "F.Cu")
			(hatch none 0.5)
			(connect_pads
				(clearance 0)
			)
			(min_thickness 0.25)
			(keepout
				(tracks not_allowed)
				(vias allowed)
				(pads allowed)
				(copperpour not_allowed)
				(footprints allowed)
			)
			(placement
				(enabled no)
				(sheetname "")
			)
			(fill
				(thermal_gap 0.5)
				(thermal_bridge_width 0.5)
				(island_removal_mode 0)
			)
			(polygon
				(pts
					(xy 486.957624 -275.648674) (xy 479.883724 -275.648674) (xy 479.883724 -282.582874) (xy 480.988624 -282.582874)
					(xy 480.988624 -278.468074) (xy 485.611424 -278.468074) (xy 485.611424 -282.582874) (xy 486.957624 -282.582874)
				)
			)
		)
		(zone
			(layer "F.Cu")
			(hatch none 0.5)
			(connect_pads
				(clearance 0)
			)
			(min_thickness 0.25)
			(keepout
				(tracks allowed)
				(vias not_allowed)
				(pads allowed)
				(copperpour not_allowed)
				(footprints allowed)
			)
			(placement
				(enabled no)
				(sheetname "")
			)
			(fill
				(thermal_gap 0.5)
				(thermal_bridge_width 0.5)
				(island_removal_mode 0)
			)
			(polygon
				(pts
					(xy 486.957624 -275.648674) (xy 479.883724 -275.648674) (xy 479.883724 -282.582874) (xy 480.988624 -282.582874)
					(xy 480.988624 -278.468074) (xy 485.611424 -278.468074) (xy 485.611424 -282.582874) (xy 486.957624 -282.582874)
				)
			)
		)
		(zone
			(layer "F.Cu")
			(hatch none 0.5)
			(connect_pads
				(clearance 0)
			)
			(min_thickness 0.25)
			(keepout
				(tracks allowed)
				(vias not_allowed)
				(pads allowed)
				(copperpour not_allowed)
				(footprints allowed)
			)
			(placement
				(enabled no)
				(sheetname "")
			)
			(fill
				(thermal_gap 0.5)
				(thermal_bridge_width 0.5)
				(island_removal_mode 0)
			)
			(polygon
				(pts
					(xy 486.957624 -242.171474) (xy 479.883724 -242.171474) (xy 479.883724 -235.237274) (xy 480.988624 -235.237274)
					(xy 480.988624 -239.352074) (xy 485.611424 -239.352074) (xy 485.611424 -235.237274) (xy 486.957624 -235.237274)
				)
			)
		)
		(zone
			(layer "F.Cu")
			(hatch none 0.5)
			(connect_pads
				(clearance 0)
			)
			(min_thickness 0.25)
			(keepout
				(tracks not_allowed)
				(vias allowed)
				(pads allowed)
				(copperpour not_allowed)
				(footprints allowed)
			)
			(placement
				(enabled no)
				(sheetname "")
			)
			(fill
				(thermal_gap 0.5)
				(thermal_bridge_width 0.5)
				(island_removal_mode 0)
			)
			(polygon
				(pts
					(xy 486.957624 -242.171474) (xy 479.883724 -242.171474) (xy 479.883724 -235.237274) (xy 480.988624 -235.237274)
					(xy 480.988624 -239.352074) (xy 485.611424 -239.352074) (xy 485.611424 -235.237274) (xy 486.957624 -235.237274)
				)
			)
		)
		(zone
			(layers "F.Cu" "B.Cu" "In1.Cu" "In2.Cu" "In3.Cu" "In4.Cu" "In5.Cu" "In6.Cu")
			(hatch none 0.5)
			(connect_pads
				(clearance 0)
			)
			(min_thickness 0.25)
			(keepout
				(tracks not_allowed)
				(vias allowed)
				(pads allowed)
				(copperpour not_allowed)
				(footprints allowed)
			)
			(placement
				(enabled no)
				(sheetname "")
			)
			(fill
				(thermal_gap 0.5)
				(thermal_bridge_width 0.5)
				(island_removal_mode 0)
			)
			(polygon
				(pts
					(arc
						(start 484.074724 -240.03508)
						(mid 482.525324 -240.03508)
						(end 484.074724 -240.03508)
					)
				)
			)
		)
		(zone
			(layers "F.Cu" "B.Cu" "In1.Cu" "In2.Cu" "In3.Cu" "In4.Cu" "In5.Cu" "In6.Cu")
			(hatch none 0.5)
			(connect_pads
				(clearance 0)
			)
			(min_thickness 0.25)
			(keepout
				(tracks not_allowed)
				(vias allowed)
				(pads allowed)
				(copperpour not_allowed)
				(footprints allowed)
			)
			(placement
				(enabled no)
				(sheetname "")
			)
			(fill
				(thermal_gap 0.5)
				(thermal_bridge_width 0.5)
				(island_removal_mode 0)
			)
			(polygon
				(pts
					(arc
						(start 484.277924 -277.785068)
						(mid 482.322124 -277.785068)
						(end 484.277924 -277.785068)
					)
				)
			)
		)
	)
	(footprint ""
		(layer "F.Cu")
		(at 114.681 -262.001 -90)
		(property "Reference" "C70"
			(at 0 0 270)
			(layer "F.SilkS")
			(hide yes)
			(effects
				(font
					(size 1.27 1.27)
				)
			)
		)
		(property "Value" "SC10U16V6KX-2GP"
			(at -0.0762 -5.1308 270)
			(unlocked yes)
			(layer "F.Fab")
			(hide yes)
			(effects
				(font
					(size 1.016 1.016)
					(thickness 0.1524)
				)
			)
		)
		(property "Device Type" "C1206H71"
			(at -0.127 -6.6548 270)
			(unlocked yes)
			(layer "F.Fab")
			(hide yes)
			(effects
				(font
					(size 1.016 1.016)
					(thickness 0.1524)
				)
			)
		)
		(duplicate_pad_numbers_are_jumpers no)
		(fp_line
			(start -1.016 2.2352)
			(end -1.016 0.8382)
			(stroke
				(width 0.1524)
				(type default)
			)
			(layer "F.SilkS")
		)
		(fp_line
			(start 1.016 2.2352)
			(end -1.016 2.2352)
			(stroke
				(width 0.1524)
				(type default)
			)
			(layer "F.SilkS")
		)
		(fp_line
			(start 1.016 0.8382)
			(end 1.016 2.2352)
			(stroke
				(width 0.1524)
				(type default)
			)
			(layer "F.SilkS")
		)
		(fp_line
			(start -1.016 -0.8382)
			(end -1.016 -2.2352)
			(stroke
				(width 0.1524)
				(type default)
			)
			(layer "F.SilkS")
		)
		(fp_line
			(start -1.016 -2.2352)
			(end 1.016 -2.2352)
			(stroke
				(width 0.1524)
				(type default)
			)
			(layer "F.SilkS")
		)
		(fp_line
			(start 1.016 -2.2352)
			(end 1.016 -0.8382)
			(stroke
				(width 0.1524)
				(type default)
			)
			(layer "F.SilkS")
		)
		(fp_rect
			(start -1.0922 2.3114)
			(end 1.0922 -2.3114)
			(stroke
				(width 0)
				(type default)
			)
			(fill no)
			(layer "F.CrtYd")
		)
		(fp_poly
			(pts
				(xy 1.0922 -2.3114) (xy 1.0922 2.3114) (xy -1.0922 2.3114) (xy -1.0922 -2.3114)
			)
			(stroke
				(width 0)
				(type default)
			)
			(fill no)
			(layer "F.Fab")
		)
		(pad "1" smd rect
			(at 0 -1.397 270)
			(size 1.651 1.27)
			(layers "F.Cu" "F.Mask" "F.Paste")
			(net "P5V_HDD3")
		)
		(pad "2" smd rect
			(at 0 1.397 270)
			(size 1.651 1.27)
			(layers "F.Cu" "F.Mask" "F.Paste")
			(net "GND")
		)
	)
	(footprint ""
		(layer "F.Cu")
		(at 258.938522 -363.575346 90)
		(property "Reference" "R1034"
			(at 0 0 90)
			(layer "F.SilkS")
			(hide yes)
			(effects
				(font
					(size 1.27 1.27)
				)
			)
		)
		(property "Value" "0R2J-2-GP"
			(at 0.064008 -3.993896 90)
			(unlocked yes)
			(layer "F.Fab")
			(hide yes)
			(effects
				(font
					(size 1.016 1.016)
					(thickness 0.1524)
				)
			)
		)
		(property "Device Type" "R402H16"
			(at 0.064008 -5.517896 90)
			(unlocked yes)
			(layer "F.Fab")
			(hide yes)
			(effects
				(font
					(size 1.016 1.016)
					(thickness 0.1524)
				)
			)
		)
		(duplicate_pad_numbers_are_jumpers no)
		(fp_line
			(start 0.508 -0.9398)
			(end -0.508 -0.9398)
			(stroke
				(width 0.1524)
				(type default)
			)
			(layer "F.SilkS")
		)
		(fp_line
			(start -0.508 -0.9398)
			(end -0.508 0.9398)
			(stroke
				(width 0.1524)
				(type default)
			)
			(layer "F.SilkS")
		)
		(fp_rect
			(start -0.508 0.9398)
			(end 0.508 -0.9398)
			(stroke
				(width 0)
				(type default)
			)
			(fill no)
			(layer "F.CrtYd")
		)
		(fp_rect
			(start -0.508 0.9398)
			(end 0.508 -0.9398)
			(stroke
				(width 0)
				(type default)
			)
			(fill no)
			(layer "F.Fab")
		)
		(pad "1" smd custom
			(at 0 -0.4445 90)
			(size 0.1397 0.1397)
			(layers "F.Cu" "F.Mask" "F.Paste")
			(net "MB3_SPISS_PD")
			(options
				(clearance outline)
				(anchor circle)
			)
			(primitives
				(gr_poly
					(pts
						(arc
							(start -0.1778 -0.2794)
							(mid -0.249642 -0.249642)
							(end -0.2794 -0.1778)
						)
						(arc
							(start -0.2794 0.1778)
							(mid -0.249642 0.249642)
							(end -0.1778 0.2794)
						)
						(arc
							(start 0.1778 0.2794)
							(mid 0.249642 0.249642)
							(end 0.2794 0.1778)
						)
						(arc
							(start 0.2794 -0.1778)
							(mid 0.249642 -0.249642)
							(end 0.1778 -0.2794)
						)
					)
					(width 0)
					(fill yes)
				)
			)
		)
		(pad "2" smd custom
			(at 0 0.4445 90)
			(size 0.1397 0.1397)
			(layers "F.Cu" "F.Mask" "F.Paste")
			(net "AGND_CURRENT_DPB")
			(options
				(clearance outline)
				(anchor circle)
			)
			(primitives
				(gr_poly
					(pts
						(arc
							(start -0.1778 -0.2794)
							(mid -0.249642 -0.249642)
							(end -0.2794 -0.1778)
						)
						(arc
							(start -0.2794 0.1778)
							(mid -0.249642 0.249642)
							(end -0.1778 0.2794)
						)
						(arc
							(start 0.1778 0.2794)
							(mid 0.249642 0.249642)
							(end 0.2794 0.1778)
						)
						(arc
							(start 0.2794 -0.1778)
							(mid 0.249642 -0.249642)
							(end 0.1778 -0.2794)
						)
					)
					(width 0)
					(fill yes)
				)
			)
		)
	)
)
